(kicad_pcb
	(version 20260206)
	(generator "pcbnew")
	(generator_version "10.0")
	(general
		(thickness 1.6)
		(legacy_teardrops no)
	)
	(paper "A4")
	(title_block
		(title "03242023_DA0F0TMBIJ0_F0T_Motherboard_J_brd_V01_OCP.brd")
		(comment 1 "Grand Teton / footprints 2665-2671 of 6105")
	)
	(layers
		(0 "F.Cu" signal "TOP")
		(4 "In1.Cu" signal "GND")
		(6 "In2.Cu" signal "IN1")
		(8 "In3.Cu" signal "GND1")
		(10 "In4.Cu" signal "IN2")
		(12 "In5.Cu" signal "GND2")
		(14 "In6.Cu" signal "IN3")
		(16 "In7.Cu" signal "GND3")
		(18 "In8.Cu" signal "VCC")
		(20 "In9.Cu" signal "VCC1")
		(22 "In10.Cu" signal "GND4")
		(24 "In11.Cu" signal "IN4")
		(26 "In12.Cu" signal "GND5")
		(28 "In13.Cu" signal "IN5")
		(30 "In14.Cu" signal "GND6")
		(32 "In15.Cu" signal "IN6")
		(34 "In16.Cu" signal "GND7")
		(2 "B.Cu" signal "BOTTOM")
		(9 "F.Adhes" user "F.Adhesive")
		(11 "B.Adhes" user "B.Adhesive")
		(13 "F.Paste" user "Package Geometry/Pastemask Top")
		(15 "B.Paste" user "Package Geometry/Pastemask Bottom")
		(5 "F.SilkS" user "Ref Des/Silkscreen Top")
		(7 "B.SilkS" user "Ref Des/Silkscreen Bottom")
		(1 "F.Mask" user "Board Geometry/Soldermask Top")
		(3 "B.Mask" user "Board Geometry/Soldermask Bottom")
		(17 "Dwgs.User" user "User.Drawings")
		(19 "Cmts.User" user "User.Comments")
		(21 "Eco1.User" user "User.Eco1")
		(23 "Eco2.User" user "User.Eco2")
		(25 "Edge.Cuts" user "Board Geometry/Outline")
		(27 "Margin" user)
		(31 "F.CrtYd" user "Package Geometry/Place Bound Top")
		(29 "B.CrtYd" user "Package Geometry/Place Bound Bottom")
		(35 "F.Fab" user "Ref Des/Assembly Top")
		(33 "B.Fab" user "Ref Des/Assembly Bottom")
	)
	(footprint ""
		(layer "F.Cu")
		(at 105.944416 -338.180172 90)
		(property "Reference" "PR1766"
			(at 0 0 90)
			(layer "F.SilkS")
			(hide yes)
			(effects
				(font
					(size 1.27 1.27)
				)
			)
		)
		(property "Value" ""
			(at 0 0 90)
			(layer "F.Fab")
			(effects
				(font
					(size 1.27 1.27)
				)
			)
		)
		(duplicate_pad_numbers_are_jumpers no)
		(fp_line
			(start 0.7874 -0.4064)
			(end 0.7874 0.4064)
			(stroke
				(width 0.1524)
				(type default)
			)
			(layer "F.SilkS")
		)
		(fp_line
			(start -0.7874 -0.4064)
			(end 0.7874 -0.4064)
			(stroke
				(width 0.1524)
				(type default)
			)
			(layer "F.SilkS")
		)
		(fp_line
			(start 0.7874 0.4064)
			(end -0.7874 0.4064)
			(stroke
				(width 0.1524)
				(type default)
			)
			(layer "F.SilkS")
		)
		(fp_line
			(start -0.7874 0.4064)
			(end -0.7874 -0.4064)
			(stroke
				(width 0.1524)
				(type default)
			)
			(layer "F.SilkS")
		)
		(fp_line
			(start -0.12065 -0.305054)
			(end -0.12065 -0.2794)
			(stroke
				(width 0.1)
				(type default)
			)
			(layer "F.Fab")
		)
		(fp_line
			(start -0.67945 -0.305054)
			(end -0.12065 -0.305054)
			(stroke
				(width 0.1)
				(type default)
			)
			(layer "F.Fab")
		)
		(fp_line
			(start 0.67945 -0.3048)
			(end 0.67945 0.3048)
			(stroke
				(width 0.1)
				(type default)
			)
			(layer "F.Fab")
		)
		(fp_line
			(start 0.12065 -0.3048)
			(end 0.67945 -0.3048)
			(stroke
				(width 0.1)
				(type default)
			)
			(layer "F.Fab")
		)
		(fp_line
			(start 0.12065 -0.2794)
			(end 0.12065 -0.3048)
			(stroke
				(width 0.1)
				(type default)
			)
			(layer "F.Fab")
		)
		(fp_line
			(start -0.12065 -0.2794)
			(end 0.12065 -0.2794)
			(stroke
				(width 0.1)
				(type default)
			)
			(layer "F.Fab")
		)
		(fp_line
			(start 0.120396 0.2794)
			(end -0.12065 0.2794)
			(stroke
				(width 0.1)
				(type default)
			)
			(layer "F.Fab")
		)
		(fp_line
			(start -0.12065 0.2794)
			(end -0.12065 0.3048)
			(stroke
				(width 0.1)
				(type default)
			)
			(layer "F.Fab")
		)
		(fp_line
			(start 0.67945 0.3048)
			(end 0.120396 0.3048)
			(stroke
				(width 0.1)
				(type default)
			)
			(layer "F.Fab")
		)
		(fp_line
			(start 0.120396 0.3048)
			(end 0.120396 0.2794)
			(stroke
				(width 0.1)
				(type default)
			)
			(layer "F.Fab")
		)
		(fp_line
			(start -0.12065 0.3048)
			(end -0.67945 0.3048)
			(stroke
				(width 0.1)
				(type default)
			)
			(layer "F.Fab")
		)
		(fp_line
			(start -0.67945 0.3048)
			(end -0.67945 -0.305054)
			(stroke
				(width 0.1)
				(type default)
			)
			(layer "F.Fab")
		)
		(pad "1" smd circle
			(at -0.40005 0 90)
			(size 0 0)
			(layers "F.Cu" "F.Mask" "F.Paste")
			(net "SW_PVCCIN_CPU1_BOOT2")
		)
		(pad "2" smd circle
			(at 0.40005 0 90)
			(size 0 0)
			(layers "F.Cu" "F.Mask" "F.Paste")
			(net "SW_PVCCIN_CPU1_BOOT2_R")
		)
	)
	(footprint ""
		(layer "F.Cu")
		(at 216.065608 -401.775422 180)
		(property "Reference" "PR3986"
			(at 0 0 180)
			(layer "F.SilkS")
			(hide yes)
			(effects
				(font
					(size 1.27 1.27)
				)
			)
		)
		(property "Value" ""
			(at 0 0 180)
			(layer "F.Fab")
			(effects
				(font
					(size 1.27 1.27)
				)
			)
		)
		(duplicate_pad_numbers_are_jumpers no)
		(fp_line
			(start 0.7874 0.4064)
			(end -0.7874 0.4064)
			(stroke
				(width 0.1524)
				(type default)
			)
			(layer "F.SilkS")
		)
		(fp_line
			(start 0.7874 -0.4064)
			(end 0.7874 0.4064)
			(stroke
				(width 0.1524)
				(type default)
			)
			(layer "F.SilkS")
		)
		(fp_line
			(start -0.7874 0.4064)
			(end -0.7874 -0.4064)
			(stroke
				(width 0.1524)
				(type default)
			)
			(layer "F.SilkS")
		)
		(fp_line
			(start -0.7874 -0.4064)
			(end 0.7874 -0.4064)
			(stroke
				(width 0.1524)
				(type default)
			)
			(layer "F.SilkS")
		)
		(fp_line
			(start 0.67945 0.3048)
			(end 0.120396 0.3048)
			(stroke
				(width 0.1)
				(type default)
			)
			(layer "F.Fab")
		)
		(fp_line
			(start 0.67945 -0.3048)
			(end 0.67945 0.3048)
			(stroke
				(width 0.1)
				(type default)
			)
			(layer "F.Fab")
		)
		(fp_line
			(start 0.12065 -0.2794)
			(end 0.12065 -0.3048)
			(stroke
				(width 0.1)
				(type default)
			)
			(layer "F.Fab")
		)
		(fp_line
			(start 0.12065 -0.3048)
			(end 0.67945 -0.3048)
			(stroke
				(width 0.1)
				(type default)
			)
			(layer "F.Fab")
		)
		(fp_line
			(start 0.120396 0.3048)
			(end 0.120396 0.2794)
			(stroke
				(width 0.1)
				(type default)
			)
			(layer "F.Fab")
		)
		(fp_line
			(start 0.120396 0.2794)
			(end -0.12065 0.2794)
			(stroke
				(width 0.1)
				(type default)
			)
			(layer "F.Fab")
		)
		(fp_line
			(start -0.12065 0.3048)
			(end -0.67945 0.3048)
			(stroke
				(width 0.1)
				(type default)
			)
			(layer "F.Fab")
		)
		(fp_line
			(start -0.12065 0.2794)
			(end -0.12065 0.3048)
			(stroke
				(width 0.1)
				(type default)
			)
			(layer "F.Fab")
		)
		(fp_line
			(start -0.12065 -0.2794)
			(end 0.12065 -0.2794)
			(stroke
				(width 0.1)
				(type default)
			)
			(layer "F.Fab")
		)
		(fp_line
			(start -0.12065 -0.305054)
			(end -0.12065 -0.2794)
			(stroke
				(width 0.1)
				(type default)
			)
			(layer "F.Fab")
		)
		(fp_line
			(start -0.67945 0.3048)
			(end -0.67945 -0.305054)
			(stroke
				(width 0.1)
				(type default)
			)
			(layer "F.Fab")
		)
		(fp_line
			(start -0.67945 -0.305054)
			(end -0.12065 -0.305054)
			(stroke
				(width 0.1)
				(type default)
			)
			(layer "F.Fab")
		)
		(pad "1" smd circle
			(at -0.40005 0 180)
			(size 0 0)
			(layers "F.Cu" "F.Mask" "F.Paste")
			(net "HSC_CS_3")
		)
		(pad "2" smd circle
			(at 0.40005 0 180)
			(size 0 0)
			(layers "F.Cu" "F.Mask" "F.Paste")
			(net "AGND_HSC")
		)
	)
	(footprint ""
		(layer "F.Cu")
		(at 25.636474 -178.759358 90)
		(property "Reference" "PR4272"
			(at 0 0 90)
			(layer "F.SilkS")
			(hide yes)
			(effects
				(font
					(size 1.27 1.27)
				)
			)
		)
		(property "Value" ""
			(at 0 0 90)
			(layer "F.Fab")
			(effects
				(font
					(size 1.27 1.27)
				)
			)
		)
		(duplicate_pad_numbers_are_jumpers no)
		(fp_line
			(start 0.7874 -0.4064)
			(end 0.7874 0.4064)
			(stroke
				(width 0.1524)
				(type default)
			)
			(layer "F.SilkS")
		)
		(fp_line
			(start -0.7874 -0.4064)
			(end 0.7874 -0.4064)
			(stroke
				(width 0.1524)
				(type default)
			)
			(layer "F.SilkS")
		)
		(fp_line
			(start 0.7874 0.4064)
			(end -0.7874 0.4064)
			(stroke
				(width 0.1524)
				(type default)
			)
			(layer "F.SilkS")
		)
		(fp_line
			(start -0.7874 0.4064)
			(end -0.7874 -0.4064)
			(stroke
				(width 0.1524)
				(type default)
			)
			(layer "F.SilkS")
		)
		(fp_line
			(start -0.12065 -0.305054)
			(end -0.12065 -0.2794)
			(stroke
				(width 0.1)
				(type default)
			)
			(layer "F.Fab")
		)
		(fp_line
			(start -0.67945 -0.305054)
			(end -0.12065 -0.305054)
			(stroke
				(width 0.1)
				(type default)
			)
			(layer "F.Fab")
		)
		(fp_line
			(start 0.67945 -0.3048)
			(end 0.67945 0.3048)
			(stroke
				(width 0.1)
				(type default)
			)
			(layer "F.Fab")
		)
		(fp_line
			(start 0.12065 -0.3048)
			(end 0.67945 -0.3048)
			(stroke
				(width 0.1)
				(type default)
			)
			(layer "F.Fab")
		)
		(fp_line
			(start 0.12065 -0.2794)
			(end 0.12065 -0.3048)
			(stroke
				(width 0.1)
				(type default)
			)
			(layer "F.Fab")
		)
		(fp_line
			(start -0.12065 -0.2794)
			(end 0.12065 -0.2794)
			(stroke
				(width 0.1)
				(type default)
			)
			(layer "F.Fab")
		)
		(fp_line
			(start 0.120396 0.2794)
			(end -0.12065 0.2794)
			(stroke
				(width 0.1)
				(type default)
			)
			(layer "F.Fab")
		)
		(fp_line
			(start -0.12065 0.2794)
			(end -0.12065 0.3048)
			(stroke
				(width 0.1)
				(type default)
			)
			(layer "F.Fab")
		)
		(fp_line
			(start 0.67945 0.3048)
			(end 0.120396 0.3048)
			(stroke
				(width 0.1)
				(type default)
			)
			(layer "F.Fab")
		)
		(fp_line
			(start 0.120396 0.3048)
			(end 0.120396 0.2794)
			(stroke
				(width 0.1)
				(type default)
			)
			(layer "F.Fab")
		)
		(fp_line
			(start -0.12065 0.3048)
			(end -0.67945 0.3048)
			(stroke
				(width 0.1)
				(type default)
			)
			(layer "F.Fab")
		)
		(fp_line
			(start -0.67945 0.3048)
			(end -0.67945 -0.305054)
			(stroke
				(width 0.1)
				(type default)
			)
			(layer "F.Fab")
		)
		(pad "1" smd circle
			(at -0.40005 0 90)
			(size 0 0)
			(layers "F.Cu" "F.Mask" "F.Paste")
			(net "SW_PVNN_MAIN_CPU1_BST")
		)
		(pad "2" smd circle
			(at 0.40005 0 90)
			(size 0 0)
			(layers "F.Cu" "F.Mask" "F.Paste")
			(net "SW_PVNN_MAIN_CPU1_BST_R")
		)
	)
	(footprint ""
		(layer "F.Cu")
		(at 118.83898 -411.131004)
		(property "Reference" "R4492"
			(at 0 0 0)
			(layer "F.SilkS")
			(hide yes)
			(effects
				(font
					(size 1.27 1.27)
				)
			)
		)
		(property "Value" ""
			(at 0 0 0)
			(layer "F.Fab")
			(effects
				(font
					(size 1.27 1.27)
				)
			)
		)
		(duplicate_pad_numbers_are_jumpers no)
		(fp_line
			(start -0.7874 -0.4064)
			(end 0.7874 -0.4064)
			(stroke
				(width 0.1524)
				(type default)
			)
			(layer "F.SilkS")
		)
		(fp_line
			(start -0.7874 0.4064)
			(end -0.7874 -0.4064)
			(stroke
				(width 0.1524)
				(type default)
			)
			(layer "F.SilkS")
		)
		(fp_line
			(start 0.7874 -0.4064)
			(end 0.7874 0.4064)
			(stroke
				(width 0.1524)
				(type default)
			)
			(layer "F.SilkS")
		)
		(fp_line
			(start 0.7874 0.4064)
			(end -0.7874 0.4064)
			(stroke
				(width 0.1524)
				(type default)
			)
			(layer "F.SilkS")
		)
		(fp_line
			(start -0.67945 -0.305054)
			(end -0.12065 -0.305054)
			(stroke
				(width 0.1)
				(type default)
			)
			(layer "F.Fab")
		)
		(fp_line
			(start -0.67945 0.3048)
			(end -0.67945 -0.305054)
			(stroke
				(width 0.1)
				(type default)
			)
			(layer "F.Fab")
		)
		(fp_line
			(start -0.12065 -0.305054)
			(end -0.12065 -0.2794)
			(stroke
				(width 0.1)
				(type default)
			)
			(layer "F.Fab")
		)
		(fp_line
			(start -0.12065 -0.2794)
			(end 0.12065 -0.2794)
			(stroke
				(width 0.1)
				(type default)
			)
			(layer "F.Fab")
		)
		(fp_line
			(start -0.12065 0.2794)
			(end -0.12065 0.3048)
			(stroke
				(width 0.1)
				(type default)
			)
			(layer "F.Fab")
		)
		(fp_line
			(start -0.12065 0.3048)
			(end -0.67945 0.3048)
			(stroke
				(width 0.1)
				(type default)
			)
			(layer "F.Fab")
		)
		(fp_line
			(start 0.120396 0.2794)
			(end -0.12065 0.2794)
			(stroke
				(width 0.1)
				(type default)
			)
			(layer "F.Fab")
		)
		(fp_line
			(start 0.120396 0.3048)
			(end 0.120396 0.2794)
			(stroke
				(width 0.1)
				(type default)
			)
			(layer "F.Fab")
		)
		(fp_line
			(start 0.12065 -0.3048)
			(end 0.67945 -0.3048)
			(stroke
				(width 0.1)
				(type default)
			)
			(layer "F.Fab")
		)
		(fp_line
			(start 0.12065 -0.2794)
			(end 0.12065 -0.3048)
			(stroke
				(width 0.1)
				(type default)
			)
			(layer "F.Fab")
		)
		(fp_line
			(start 0.67945 -0.3048)
			(end 0.67945 0.3048)
			(stroke
				(width 0.1)
				(type default)
			)
			(layer "F.Fab")
		)
		(fp_line
			(start 0.67945 0.3048)
			(end 0.120396 0.3048)
			(stroke
				(width 0.1)
				(type default)
			)
			(layer "F.Fab")
		)
		(pad "1" smd circle
			(at -0.40005 0)
			(size 0 0)
			(layers "F.Cu" "F.Mask" "F.Paste")
			(net "CLK_9ZXL045_HIBW")
		)
		(pad "2" smd circle
			(at 0.40005 0)
			(size 0 0)
			(layers "F.Cu" "F.Mask" "F.Paste")
			(net "GND")
		)
	)
	(footprint ""
		(layer "F.Cu")
		(at 26.6446 -409.0416 90)
		(property "Reference" "R3475"
			(at 0 0 90)
			(layer "F.SilkS")
			(hide yes)
			(effects
				(font
					(size 1.27 1.27)
				)
			)
		)
		(property "Value" ""
			(at 0 0 90)
			(layer "F.Fab")
			(effects
				(font
					(size 1.27 1.27)
				)
			)
		)
		(duplicate_pad_numbers_are_jumpers no)
		(fp_line
			(start 0.7874 -0.4064)
			(end 0.7874 0.4064)
			(stroke
				(width 0.1524)
				(type default)
			)
			(layer "F.SilkS")
		)
		(fp_line
			(start -0.7874 -0.4064)
			(end 0.7874 -0.4064)
			(stroke
				(width 0.1524)
				(type default)
			)
			(layer "F.SilkS")
		)
		(fp_line
			(start 0.7874 0.4064)
			(end -0.7874 0.4064)
			(stroke
				(width 0.1524)
				(type default)
			)
			(layer "F.SilkS")
		)
		(fp_line
			(start -0.7874 0.4064)
			(end -0.7874 -0.4064)
			(stroke
				(width 0.1524)
				(type default)
			)
			(layer "F.SilkS")
		)
		(fp_line
			(start -0.12065 -0.305054)
			(end -0.12065 -0.2794)
			(stroke
				(width 0.1)
				(type default)
			)
			(layer "F.Fab")
		)
		(fp_line
			(start -0.67945 -0.305054)
			(end -0.12065 -0.305054)
			(stroke
				(width 0.1)
				(type default)
			)
			(layer "F.Fab")
		)
		(fp_line
			(start 0.67945 -0.3048)
			(end 0.67945 0.3048)
			(stroke
				(width 0.1)
				(type default)
			)
			(layer "F.Fab")
		)
		(fp_line
			(start 0.12065 -0.3048)
			(end 0.67945 -0.3048)
			(stroke
				(width 0.1)
				(type default)
			)
			(layer "F.Fab")
		)
		(fp_line
			(start 0.12065 -0.2794)
			(end 0.12065 -0.3048)
			(stroke
				(width 0.1)
				(type default)
			)
			(layer "F.Fab")
		)
		(fp_line
			(start -0.12065 -0.2794)
			(end 0.12065 -0.2794)
			(stroke
				(width 0.1)
				(type default)
			)
			(layer "F.Fab")
		)
		(fp_line
			(start 0.120396 0.2794)
			(end -0.12065 0.2794)
			(stroke
				(width 0.1)
				(type default)
			)
			(layer "F.Fab")
		)
		(fp_line
			(start -0.12065 0.2794)
			(end -0.12065 0.3048)
			(stroke
				(width 0.1)
				(type default)
			)
			(layer "F.Fab")
		)
		(fp_line
			(start 0.67945 0.3048)
			(end 0.120396 0.3048)
			(stroke
				(width 0.1)
				(type default)
			)
			(layer "F.Fab")
		)
		(fp_line
			(start 0.120396 0.3048)
			(end 0.120396 0.2794)
			(stroke
				(width 0.1)
				(type default)
			)
			(layer "F.Fab")
		)
		(fp_line
			(start -0.12065 0.3048)
			(end -0.67945 0.3048)
			(stroke
				(width 0.1)
				(type default)
			)
			(layer "F.Fab")
		)
		(fp_line
			(start -0.67945 0.3048)
			(end -0.67945 -0.305054)
			(stroke
				(width 0.1)
				(type default)
			)
			(layer "F.Fab")
		)
		(pad "1" smd circle
			(at -0.40005 0 90)
			(size 0 0)
			(layers "F.Cu" "F.Mask" "F.Paste")
			(net "P3V3_AUX")
		)
		(pad "2" smd circle
			(at 0.40005 0 90)
			(size 0 0)
			(layers "F.Cu" "F.Mask" "F.Paste")
			(net "GPU_PRSNT_N_ISO")
		)
	)
	(footprint ""
		(layer "F.Cu")
		(at 317.122048 -402.371052 -90)
		(property "Reference" "C1571"
			(at 0 0 270)
			(layer "F.SilkS")
			(hide yes)
			(effects
				(font
					(size 1.27 1.27)
				)
			)
		)
		(property "Value" ""
			(at 0 0 270)
			(layer "F.Fab")
			(effects
				(font
					(size 1.27 1.27)
				)
			)
		)
		(duplicate_pad_numbers_are_jumpers no)
		(fp_line
			(start -0.299974 0.150114)
			(end -0.299974 -0.150114)
			(stroke
				(width 0.1)
				(type default)
			)
			(layer "F.Fab")
		)
		(fp_line
			(start 0.299974 0.150114)
			(end -0.299974 0.150114)
			(stroke
				(width 0.1)
				(type default)
			)
			(layer "F.Fab")
		)
		(fp_line
			(start -0.299974 -0.150114)
			(end 0.299974 -0.150114)
			(stroke
				(width 0.1)
				(type default)
			)
			(layer "F.Fab")
		)
		(fp_line
			(start 0.299974 -0.150114)
			(end 0.299974 0.150114)
			(stroke
				(width 0.1)
				(type default)
			)
			(layer "F.Fab")
		)
		(pad "1" smd rect
			(at -0.2667 0 270)
			(size 0.3048 0.381)
			(layers "F.Cu" "F.Mask" "F.Paste")
			(net "P5E_CPU0_PE4_TX_C_DP<4>")
		)
		(pad "2" smd rect
			(at 0.2667 0 270)
			(size 0.3048 0.381)
			(layers "F.Cu" "F.Mask" "F.Paste")
			(net "P5E_CPU0_PE4_TX_DP<4>")
		)
	)
	(footprint ""
		(layer "F.Cu")
		(at 362.646468 -359.94975)
		(property "Reference" "PC329"
			(at 0 0 0)
			(layer "F.SilkS")
			(hide yes)
			(effects
				(font
					(size 1.27 1.27)
				)
			)
		)
		(property "Value" ""
			(at 0 0 0)
			(layer "F.Fab")
			(effects
				(font
					(size 1.27 1.27)
				)
			)
		)
		(duplicate_pad_numbers_are_jumpers no)
		(fp_line
			(start -0.7874 -0.4064)
			(end 0.7874 -0.4064)
			(stroke
				(width 0.1524)
				(type default)
			)
			(layer "F.SilkS")
		)
		(fp_line
			(start -0.7874 0.4064)
			(end -0.7874 -0.4064)
			(stroke
				(width 0.1524)
				(type default)
			)
			(layer "F.SilkS")
		)
		(fp_line
			(start 0.7874 -0.4064)
			(end 0.7874 0.4064)
			(stroke
				(width 0.1524)
				(type default)
			)
			(layer "F.SilkS")
		)
		(fp_line
			(start 0.7874 0.4064)
			(end -0.7874 0.4064)
			(stroke
				(width 0.1524)
				(type default)
			)
			(layer "F.SilkS")
		)
		(fp_line
			(start -0.67945 -0.305054)
			(end -0.12065 -0.305054)
			(stroke
				(width 0.1)
				(type default)
			)
			(layer "F.Fab")
		)
		(fp_line
			(start -0.67945 0.3048)
			(end -0.67945 -0.305054)
			(stroke
				(width 0.1)
				(type default)
			)
			(layer "F.Fab")
		)
		(fp_line
			(start -0.12065 -0.305054)
			(end -0.12065 -0.2794)
			(stroke
				(width 0.1)
				(type default)
			)
			(layer "F.Fab")
		)
		(fp_line
			(start -0.12065 -0.2794)
			(end 0.12065 -0.2794)
			(stroke
				(width 0.1)
				(type default)
			)
			(layer "F.Fab")
		)
		(fp_line
			(start -0.12065 0.2794)
			(end -0.12065 0.3048)
			(stroke
				(width 0.1)
				(type default)
			)
			(layer "F.Fab")
		)
		(fp_line
			(start -0.12065 0.3048)
			(end -0.67945 0.3048)
			(stroke
				(width 0.1)
				(type default)
			)
			(layer "F.Fab")
		)
		(fp_line
			(start 0.120396 0.2794)
			(end -0.12065 0.2794)
			(stroke
				(width 0.1)
				(type default)
			)
			(layer "F.Fab")
		)
		(fp_line
			(start 0.120396 0.3048)
			(end 0.120396 0.2794)
			(stroke
				(width 0.1)
				(type default)
			)
			(layer "F.Fab")
		)
		(fp_line
			(start 0.12065 -0.3048)
			(end 0.67945 -0.3048)
			(stroke
				(width 0.1)
				(type default)
			)
			(layer "F.Fab")
		)
		(fp_line
			(start 0.12065 -0.2794)
			(end 0.12065 -0.3048)
			(stroke
				(width 0.1)
				(type default)
			)
			(layer "F.Fab")
		)
		(fp_line
			(start 0.67945 -0.3048)
			(end 0.67945 0.3048)
			(stroke
				(width 0.1)
				(type default)
			)
			(layer "F.Fab")
		)
		(fp_line
			(start 0.67945 0.3048)
			(end 0.120396 0.3048)
			(stroke
				(width 0.1)
				(type default)
			)
			(layer "F.Fab")
		)
		(pad "1" smd circle
			(at -0.40005 0)
			(size 0 0)
			(layers "F.Cu" "F.Mask" "F.Paste")
			(net "PVCCIN_CPU0_CSPIN")
		)
		(pad "2" smd circle
			(at 0.40005 0)
			(size 0 0)
			(layers "F.Cu" "F.Mask" "F.Paste")
			(net "GND")
		)
	)
)
